# S9S_MB_2U (Grand Teton) — schematic parts with pin connectivity, parts 5876–5876 of 6093; source: Cadence DE-HDL packaged netlist (pstxprt.dat, pstxnet.dat, pstchip.dat)

U1  SOCKET4677_AZIF0045P001C01CS  SOCKET4677_AZIF0045-P001C01CS IO  pkg SOCKET4677_82X64-5XA_H466  page 44  (pins 982-1308 of 4677)
  BB71  VSS410  POWER  = GND
  BB73  UPI2_RX_DP12  IN  = UPI_CPU0_CPU1_P2P2_DP<12>
  BB75  UPI2_RX_DN15  IN  = UPI_CPU0_CPU1_P2P2_DN<15>
  BB77  VSS411  POWER  = GND
  BB79  VSS412  POWER  = GND
  BB81  UPI2_TX_DP17  OUT  = UPI_CPU1_CPU0_P2P2_DP<17>
  BB83  VSS414  POWER  = GND
  BB85  PE4_TX_DP15  OUT  = P5E_CPU1_PE4_TX_DP<15>
  BB87  VSS415  POWER  = GND
  BB89  PE4_RX_DN15  IN  = P5E_CPU1_PE4_RX_DN<15>
  BB91  VSS416  POWER  = GND
  BC1  VSS417  POWER  = GND
  BC3  UPI0_TX_DP17  OUT  = UPI_CPU1_CPU0_P0P1_DP<17>
  BC5  VSS420  POWER  = GND
  BC7  UPI0_RX_DP16  IN  = UPI_CPU0_CPU1_P1P0_DP<16>
  BC9  VSS429  POWER  = GND
  BC11  PE1_RX_DN15  IN  = P5E_CPU1_PE1_RX_DN<15>
  BC13  VSS418  POWER  = GND
  BC15  PE0_TX_DP15  OUT  = P5E_CPU1_PE0_TX_DP<15>
  BC17  VSS419  POWER  = GND
  BC19  DMI_RX_DP0  IN  = TP_DMI_CPU1_PCH_RX_C_DP<0>
  BC21  VCC_3P3_AUX0  POWER  = P3V3_AUX
  BC23  RSVD37  BI  = TP_CPU1_IFST_DONE_LVC1_R
  BC25  RSVD38  BI  = TP_I3C_MNG3_BMC_SW_SDA
  BC60  VCCINFAON35  POWER  = PVCCINFAON_CPU1
  BC62  VSS421  POWER  = GND
  BC64  RSVD39  BI  = NC_SPI_S3M_CPU1_CLK_LVC1_R
  BC66  VSS422  POWER  = GND
  BC68  PTI_DIE015  OUT  = TP_TRC_CPU1_PTI<21>
  BC70  PTI_DIE010  OUT  = TP_TRC_CPU1_PTI<16>
  BC72  VSS423  POWER  = GND
  BC74  UPI2_RX_DP23  IN  = UPI_CPU0_CPU1_P2P2_DP<23>
  BC76  VSS424  POWER  = GND
  BC78  VSS425  POWER  = GND
  BC80  UPI2_TX_DP20  OUT  = UPI_CPU1_CPU0_P2P2_DP<20>
  BC82  UPI2_TX_DN18  OUT  = UPI_CPU1_CPU0_P2P2_DN<18>
  BC84  VSS426  POWER  = GND
  BC86  VSS427  POWER  = GND
  BC88  VSS428  POWER  = GND
  BC90  VSS_VCCIN_SENSE  POWER  = VSENSE_PVCCIN_CPU1_DN
  BD2  UPI0_TX_DN17  OUT  = UPI_CPU1_CPU0_P0P1_DN<17>
  BD4  VSS433  POWER  = GND
  BD6  UPI0_RX_DP17  IN  = UPI_CPU0_CPU1_P1P0_DP<17>
  BD8  VSS434  POWER  = GND
  BD10  PE1_RX_DP15  IN  = P5E_CPU1_PE1_RX_DP<15>
  BD12  VSS430  POWER  = GND
  BD14  PE1_TX_DP15  OUT  = P5E_CPU1_PE1_TX_DP<15>
  BD16  VSS431  POWER  = GND
  BD18  DMI_RX_DP1  IN  = TP_DMI_CPU1_PCH_RX_C_DP<1>
  BD20  VSS432  POWER  = GND
  BD22  ERROR_N2  OUT  = H_CPU1_ERR2_LVC1_R_N
  BD24  PMAX_TRIGGER_IO  BI  = H_PMAX_TRIGGER_IO_CPU1
  BD26  SVIDDATA0  BI  = SVID_DIO0_CPU1
  BD61  RSVD40  BI  = NC_SPI_S3M_CPU1_IO3_LVC1_R
  BD63  RSVD41  BI  = NC_ESPI_IBL_CPU1_ALERT1_N
  BD65  RSVD42  BI  = NC_SPI_S3M_CPU1_IO2_LVC1_R
  BD67  PTI_DIE017  OUT  = TP_TRC_CPU1_PTI<23>
  BD69  PTI_DIE012  OUT  = TP_TRC_CPU1_PTI<18>
  BD71  RSVD43  BI  = NC_CPU1_MDFI_DIE01_NS1
  BD73  UPI2_RX_DN23  IN  = UPI_CPU0_CPU1_P2P2_DN<23>
  BD75  UPI2_RX_DP15  IN  = UPI_CPU0_CPU1_P2P2_DP<15>
  BD77  RSVD44  BI  = TP_CPU1_SPARE13
  BD79  UPI2_TX_DN20  OUT  = UPI_CPU1_CPU0_P2P2_DN<20>
  BD81  VSS435  POWER  = GND
  BD83  UPI2_TX_DP19  OUT  = UPI_CPU1_CPU0_P2P2_DP<19>
  BD85  VSS437  POWER  = GND
  BD87  VCCIN_SENSE  POWER  = VSENSE_PVCCIN_CPU1_DP
  BD89  VSS439  POWER  = GND
  BD91  VCCIN0  POWER  = PVCCIN_CPU1
  BE1  UPI0_TX_DP18  OUT  = UPI_CPU1_CPU0_P0P1_DP<18>
  BE3  VCCD_HV13  POWER  = PVCCD_HV_CPU1
  BE5  UPI0_RX_DN17  IN  = UPI_CPU0_CPU1_P1P0_DN<17>
  BE7  VCCD_HV14  POWER  = PVCCD_HV_CPU1
  BE9  PE1_RX_DP14  IN  = P5E_CPU1_PE1_RX_DP<14>
  BE11  VCCD_HV12  POWER  = PVCCD_HV_CPU1
  BE13  PE1_TX_DN15  OUT  = P5E_CPU1_PE1_TX_DN<15>
  BE15  VCCINFAON36  POWER  = PVCCINFAON_CPU1
  BE17  DMI_RX_DN1  IN  = TP_DMI_CPU1_PCH_RX_C_DN<1>
  BE19  VCCVNN1  POWER  = PVNN_MAIN_CPU1
  BE21  RSVD45  BI  = TP_CPU1_DIE_HVM_EN_LVC1
  BE23  RSVD46  BI  = TP_CPU1_IFST_KOT_LVC1_R
  BE25  RSVD47  BI  = TP_I3C_MNG3_BMC_SW_SCL
  BE60  VCCINFAON37  POWER  = PVCCINFAON_CPU1
  BE62  RSVD48  BI  = NC_ESPI_IBL_CPU1_ALERT0_N
  BE64  VSS440  POWER  = GND
  BE66  VSS441  POWER  = GND
  BE68  VSS442  POWER  = GND
  BE70  PTI_DIE011  OUT  = TP_TRC_CPU1_PTI<17>
  BE72  VCCFA_EHV_FIVRA27  POWER  = PVCCFA_EHV_FIVRA_CPU1
  BE74  VSS443  POWER  = GND
  BE76  VSS444  POWER  = GND
  BE78  VSS445  POWER  = GND
  BE80  UPI2_TX_DP22  OUT  = UPI_CPU1_CPU0_P2P2_DP<22>
  BE82  UPI2_TX_DN19  OUT  = UPI_CPU1_CPU0_P2P2_DN<19>
  BE84  VSS446  POWER  = GND
  BE86  VCCIN1  POWER  = PVCCIN_CPU1
  BE88  VCCIN2  POWER  = PVCCIN_CPU1
  BE90  VCCIN3  POWER  = PVCCIN_CPU1
  BF2  UPI0_TX_DN18  OUT  = UPI_CPU1_CPU0_P0P1_DN<18>
  BF4  VSS450  POWER  = GND
  BF6  UPI0_RX_DN18  IN  = UPI_CPU0_CPU1_P1P0_DN<18>
  BF8  VSS456  POWER  = GND
  BF10  PE1_RX_DN14  IN  = P5E_CPU1_PE1_RX_DN<14>
  BF12  VSS447  POWER  = GND
  BF14  PE1_TX_DN14  OUT  = P5E_CPU1_PE1_TX_DN<14>
  BF16  VSS448  POWER  = GND
  BF18  DMI_RX_DN2  IN  = TP_DMI_CPU1_PCH_RX_C_DN<2>
  BF20  VSS449  POWER  = GND
  BF22  ERROR_N0  OUT  = H_CPU1_ERR0_LVC1_R_N
  BF24  RSVD49  BI  = TP_CPU1_IFST_TRIG_LVC1_R
  BF26  SVIDCLK1  OUT  = SVID_CLK1_CPU1
  BF61  VSS451  POWER  = GND
  BF63  VSS452  POWER  = GND
  BF65  RSVD50  BI  = NC_ESPI_IBL_CPU1_CS0_N
  BF67  PTI_DIE01_STB_0  OUT  = TP_TRC_CPU1_PTI2_CLK
  BF69  PTI_DIE013  OUT  = TP_TRC_CPU1_PTI<19>
  BF71  RSVD51  BI  = NC_CPU1_MDFI_DIE01_NS0
  BF73  VSS453  POWER  = GND
  BF75  VSS454  POWER  = GND
  BF77  VCCFA_EHV_FIVRA28  POWER  = PVCCFA_EHV_FIVRA_CPU1
  BF79  VSS455  POWER  = GND
  BF81  UPI2_TX_DN21  OUT  = UPI_CPU1_CPU0_P2P2_DN<21>
  BF83  VSS457  POWER  = GND
  BF85  VCCIN4  POWER  = PVCCIN_CPU1
  BF87  VCCIN5  POWER  = PVCCIN_CPU1
  BF89  VCCIN6  POWER  = PVCCIN_CPU1
  BF91  VCCIN7  POWER  = PVCCIN_CPU1
  BG1  VSS458  POWER  = GND
  BG3  UPI0_TX_DP19  OUT  = UPI_CPU1_CPU0_P0P1_DP<19>
  BG5  VSS464  POWER  = GND
  BG7  UPI0_RX_DP18  IN  = UPI_CPU0_CPU1_P1P0_DP<18>
  BG9  VSS466  POWER  = GND
  BG11  PE1_RX_DN13  IN  = P5E_CPU1_PE1_RX_DN<13>
  BG13  VSS459  POWER  = GND
  BG15  PE1_TX_DP14  OUT  = P5E_CPU1_PE1_TX_DP<14>
  BG17  VSS460  POWER  = GND
  BG19  DMI_RX_DP2  IN  = TP_DMI_CPU1_PCH_RX_C_DP<2>
  BG21  VSS461  POWER  = GND
  BG23  VSS462  POWER  = GND
  BG25  VSS463  POWER  = GND
  BG60  VCCINFAON38  POWER  = PVCCINFAON_CPU1
  BG62  RSVD52  BI  = NC_ESPI_IBL_CPU1_CLK
  BG64  RSVD53  BI  = NC_ESPI_IBL_CPU1_RESET_N
  BG66  PTI_DIE0111  OUT  = TP_TRC_CPU1_PTI<27>
  BG68  PTI_DIE016  OUT  = TP_TRC_CPU1_PTI<22>
  BG70  VSS465  POWER  = GND
  BG72  PROC_ID0  IN  = FM_CPU1_PROC_ID0
  BG74  UPI2_RX_DN20  IN  = UPI_CPU0_CPU1_P2P2_DN<20>
  BG76  UPI2_RX_DP17  IN  = UPI_CPU0_CPU1_P2P2_DP<17>
  BG78  RSVD54  BI  = NC_CPU1_HBM3_VIEWDIG0
  BG80  UPI2_TX_DN22  OUT  = UPI_CPU1_CPU0_P2P2_DN<22>
  BG82  UPI2_TX_DP21  OUT  = UPI_CPU1_CPU0_P2P2_DP<21>
  BG84  VCCIN8  POWER  = PVCCIN_CPU1
  BG86  VCCIN9  POWER  = PVCCIN_CPU1
  BG88  VCCIN10  POWER  = PVCCIN_CPU1
  BG90  VCCIN11  POWER  = PVCCIN_CPU1
  BH2  UPI0_TX_DN19  OUT  = UPI_CPU1_CPU0_P0P1_DN<19>
  BH4  VSS470  POWER  = GND
  BH6  UPI0_RX_DP19  IN  = UPI_CPU0_CPU1_P1P0_DP<19>
  BH8  VSS475  POWER  = GND
  BH10  PE1_RX_DP13  IN  = P5E_CPU1_PE1_RX_DP<13>
  BH12  VSS467  POWER  = GND
  BH14  PE1_TX_DP13  OUT  = P5E_CPU1_PE1_TX_DP<13>
  BH16  VSS468  POWER  = GND
  BH18  DMI_RX_DP3  IN  = TP_DMI_CPU1_PCH_RX_C_DP<3>
  BH20  VSS469  POWER  = GND
  BH22  RMCA_N  BI  = H_CPU1_RMCA_LVC1_R_N
  BH24  PECI  BI  = PECI_CPU1_GTL_R
  BH26  SVIDCLK0  OUT  = SVID_CLK0_CPU1
  BH61  RESET_N  IN  = RST_CPU1_LVC1_N
  BH63  RSVD55  BI  = NC_ESPI_IBL_CPU1_OE_N
  BH65  RSVD56  BI  = NC_ESPI_IBL_CPU1_CS1_N
  BH67  VSS472  POWER  = GND
  BH69  PTI_DIE014  OUT  = TP_TRC_CPU1_PTI<20>
  BH71  PROC_ID1  IN  = FM_CPU1_PROC_ID1
  BH73  VSS473  POWER  = GND
  BH75  UPI2_RX_DN17  IN  = UPI_CPU0_CPU1_P2P2_DN<17>
  BH77  VSS474  POWER  = GND
  BH79  VCCFA_EHV_FIVRA29  POWER  = PVCCFA_EHV_FIVRA_CPU1
  BH81  VSS476  POWER  = GND
  BH83  VSS477  POWER  = GND
  BH85  VCCIN12  POWER  = PVCCIN_CPU1
  BH87  VCCIN13  POWER  = PVCCIN_CPU1
  BH89  VCCIN14  POWER  = PVCCIN_CPU1
  BH91  VCCIN15  POWER  = PVCCIN_CPU1
  BJ1  UPI0_TX_DP20  OUT  = UPI_CPU1_CPU0_P0P1_DP<20>
  BJ3  VCCD_HV16  POWER  = PVCCD_HV_CPU1
  BJ5  UPI0_RX_DN19  IN  = UPI_CPU0_CPU1_P1P0_DN<19>
  BJ7  VCCD_HV17  POWER  = PVCCD_HV_CPU1
  BJ9  PE1_RX_DP12  IN  = P5E_CPU1_PE1_RX_DP<12>
  BJ11  VCCD_HV15  POWER  = PVCCD_HV_CPU1
  BJ13  PE1_TX_DN13  OUT  = P5E_CPU1_PE1_TX_DN<13>
  BJ15  VCCINFAON39  POWER  = PVCCINFAON_CPU1
  BJ17  DMI_RX_DN3  IN  = TP_DMI_CPU1_PCH_RX_C_DN<3>
  BJ19  VCCVNN2  POWER  = PVNN_MAIN_CPU1
  BJ21  RSVD57  BI  = NC_CPU1_MDFI_DIE00_NS1
  BJ23  MBP2_N  BI  = DBP_CPU1_HOOK8_MBP2_GTL_QS_R_N
  BJ25  SVIDALERT1_N  IN  = SVID_ALERT1_CPU1_N
  BJ60  VCCINFAON40  POWER  = PVCCINFAON_CPU1
  BJ62  VSS479  POWER  = GND
  BJ64  RSVD58  BI  = NC_ESPI_IBL_CPU1_IO1
  BJ66  PTI_DIE0112  OUT  = TP_TRC_CPU1_PTI<28>
  BJ68  VSS480  POWER  = GND
  BJ70  RSVD59  BI  = CPU1_RSVD<54>
  BJ72  VCCFA_EHV_FIVRA30  POWER  = PVCCFA_EHV_FIVRA_CPU1
  BJ74  UPI2_RX_DP20  IN  = UPI_CPU0_CPU1_P2P2_DP<20>
  BJ76  UPI2_RX_DN18  IN  = UPI_CPU0_CPU1_P2P2_DN<18>
  BJ78  VCCFA_EHV_FIVRA31  POWER  = PVCCFA_EHV_FIVRA_CPU1
  BJ80  VSS481  POWER  = GND
  BJ82  VSS482  POWER  = GND
  BJ84  VSS483  POWER  = GND
  BJ86  VSS484  POWER  = GND
  BJ88  VSS485  POWER  = GND
  BJ90  VSS486  POWER  = GND
  BK2  UPI0_TX_DN20  OUT  = UPI_CPU1_CPU0_P0P1_DN<20>
  BK4  VSS490  POWER  = GND
  BK6  UPI0_RX_DN20  IN  = UPI_CPU0_CPU1_P1P0_DN<20>
  BK8  VSS496  POWER  = GND
  BK10  PE1_RX_DN12  IN  = P5E_CPU1_PE1_RX_DN<12>
  BK12  VSS487  POWER  = GND
  BK14  PE1_TX_DN12  OUT  = P5E_CPU1_PE1_TX_DN<12>
  BK16  VSS488  POWER  = GND
  BK18  DMI_RX_DN4  IN  = TP_DMI_CPU1_PCH_RX_C_DN<4>
  BK20  VSS489  POWER  = GND
  BK22  RSVD60  BI  = NC_CPU1_MDFI_DIE00_NS0
  BK24  MBP3_N  BI  = DBP_CPU1_HOOK9_MBP3_GTL_QS_R_N
  BK26  SVIDALERT0_N  IN  = SVID_ALERT0_CPU1_N
  BK61  VCCINFAON41  POWER  = PVCCINFAON_CPU1
  BK63  RSVD61  BI  = NC_ESPI_IBL_CPU1_IO0
  BK65  VSS491  POWER  = GND
  BK67  PTI_DIE01_STB_1  OUT  = TP_TRC_CPU1_PTI3_CLK
  BK69  PTI_DIE018  OUT  = TP_TRC_CPU1_PTI<24>
  BK71  VSS492  POWER  = GND
  BK73  UPI2_RX_DN22  IN  = UPI_CPU0_CPU1_P2P2_DN<22>
  BK75  VSS494  POWER  = GND
  BK77  UPI2_RX_DP18  IN  = UPI_CPU0_CPU1_P2P2_DP<18>
  BK79  VSS495  POWER  = GND
  BK81  VCCIN16  POWER  = PVCCIN_CPU1
  BK83  VCCIN17  POWER  = PVCCIN_CPU1
  BK85  VCCIN18  POWER  = PVCCIN_CPU1
  BK87  VCCIN19  POWER  = PVCCIN_CPU1
  BK89  VCCIN20  POWER  = PVCCIN_CPU1
  BK91  VCCIN21  POWER  = PVCCIN_CPU1
  BL1  VSS497  POWER  = GND
  BL3  UPI0_TX_DP21  OUT  = UPI_CPU1_CPU0_P0P1_DP<21>
  BL5  VSS500  POWER  = GND
  BL7  UPI0_RX_DP20  IN  = UPI_CPU0_CPU1_P1P0_DP<20>
  BL9  VSS505  POWER  = GND
  BL11  PE1_RX_DN11  IN  = P5E_CPU1_PE1_RX_DN<11>
  BL13  VSS498  POWER  = GND
  BL15  PE1_TX_DP12  OUT  = P5E_CPU1_PE1_TX_DP<12>
  BL17  VSS499  POWER  = GND
  BL19  DMI_RX_DP4  IN  = TP_DMI_CPU1_PCH_RX_C_DP<4>
  BL21  RSVD62  BI  = NC_CPU1_PE0_APROBE<1>
  BL23  MBP0_N  BI  = DBP_CPU1_MBP0_GTL_R_N
  BL25  SVIDDATA1  BI  = SVID_DIO1_CPU1
  BL60  RSVD63  BI  = NC_CPU1_HBM3_VIEWDIG1
  BL62  THERMTRIP_N  OUT  = H_CPU1_THERMTRIP_LVC1_R_N
  BL64  PKG_ID0  IN  = FM_CPU1_PKGID0
  BL66  PTI_DIE0113  OUT  = TP_TRC_CPU1_PTI<29>
  BL68  VSS501  POWER  = GND
  BL70  VSS502  POWER  = GND
  BL72  VSS503  POWER  = GND
  BL74  UPI2_RX_DP22  IN  = UPI_CPU0_CPU1_P2P2_DP<22>
  BL76  UPI2_RX_DN19  IN  = UPI_CPU0_CPU1_P2P2_DN<19>
  BL78  VSS504  POWER  = GND
  BL80  VCCIN22  POWER  = PVCCIN_CPU1
  BL82  VCCIN23  POWER  = PVCCIN_CPU1
  BL84  VCCIN24  POWER  = PVCCIN_CPU1
  BL86  VCCIN25  POWER  = PVCCIN_CPU1
  BL88  VCCIN26  POWER  = PVCCIN_CPU1
  BL90  VCCIN27  POWER  = PVCCIN_CPU1
  BM2  UPI0_TX_DN21  OUT  = UPI_CPU1_CPU0_P0P1_DN<21>
  BM4  VSS512  POWER  = GND
  BM6  UPI0_RX_DP21  IN  = UPI_CPU0_CPU1_P1P0_DP<21>
  BM8  VSS517  POWER  = GND
  BM10  PE1_RX_DP11  IN  = P5E_CPU1_PE1_RX_DP<11>
  BM12  VSS506  POWER  = GND
  BM14  PE1_TX_DP11  OUT  = P5E_CPU1_PE1_TX_DP<11>
  BM16  VSS507  POWER  = GND
  BM18  DMI_RX_DP5  IN  = TP_DMI_CPU1_PCH_RX_C_DP<5>
  BM20  VSS508  POWER  = GND
  BM22  VSS509  POWER  = GND
  BM24  VSS510  POWER  = GND
  BM26  VSS511  POWER  = GND
  BM61  VSS513  POWER  = GND
  BM63  RSVD64  BI  = NC_ESPI_IBL_CPU1_IO3
  BM65  RSVD65  BI  = NC_CPU1_SOC_SPARE1
  BM67  PTI_DIE0114  OUT  = TP_TRC_CPU1_PTI<30>
  BM69  PTI_DIE019  OUT  = TP_TRC_CPU1_PTI<25>
  BM71  UPI2_TX_DN23  OUT  = UPI_CPU1_CPU0_P2P2_DN<23>
  BM73  VSS515  POWER  = GND
  BM75  UPI2_RX_DP21  IN  = UPI_CPU0_CPU1_P2P2_DP<21>
  BM77  VSS516  POWER  = GND
  BM79  VCCIN28  POWER  = PVCCIN_CPU1
  BM81  VCCIN29  POWER  = PVCCIN_CPU1
  BM83  VCCIN30  POWER  = PVCCIN_CPU1
  BM85  VCCIN31  POWER  = PVCCIN_CPU1
  BM87  VCCIN32  POWER  = PVCCIN_CPU1
  BM89  VCCIN33  POWER  = PVCCIN_CPU1
  BM91  VCCIN34  POWER  = PVCCIN_CPU1
  BN3  UPI0_TX_DP22  OUT  = UPI_CPU1_CPU0_P0P1_DP<22>
  BN5  UPI0_RX_DN21  IN  = UPI_CPU0_CPU1_P1P0_DN<21>
  BN7  VCCD_HV18  POWER  = PVCCD_HV_CPU1
  BN9  PE1_RX_DP10  IN  = P5E_CPU1_PE1_RX_DP<10>
  BN11  VSS_VCCD_HV_SENSE  POWER  = VSENSE_PVCCD_HV_CPU1_DN
  BN13  PE1_TX_DN11  OUT  = P5E_CPU1_PE1_TX_DN<11>
  BN15  VCCINFAON42  POWER  = PVCCINFAON_CPU1
  BN17  DMI_RX_DN5  IN  = TP_DMI_CPU1_PCH_RX_C_DN<5>
  BN19  VCCVNN3  POWER  = PVNN_MAIN_CPU1
  BN21  RSVD66  BI  = NC_CPU1_PE0_APROBE<0>
  BN23  BMCINIT  IN  = H_CPU1_BMCINIT_LVC1
  BN25  MBP1_N  BI  = DBP_CPU1_MBP1_GTL_R_N
  BN27  PTI_DIE0012  OUT  = TP_TRC_CPU1_PTI<12>
  BN29  PTI_DIE0014  OUT  = TP_TRC_CPU1_PTI<14>
  BN31  VSS518  POWER  = GND
  BN33  VCCIN35  POWER  = PVCCIN_CPU1
  BN35  VCCIN36  POWER  = PVCCIN_CPU1
  BN37  VCCIN37  POWER  = PVCCIN_CPU1
  BN39  VCCIN38  POWER  = PVCCIN_CPU1
  BN41  VCCIN39  POWER  = PVCCIN_CPU1
  BN43  VCCIN40  POWER  = PVCCIN_CPU1
  BN45  VCCIN41  POWER  = PVCCIN_CPU1
  BN48  VCCIN42  POWER  = PVCCIN_CPU1
  BN50  VCCIN43  POWER  = PVCCIN_CPU1
  BN52  VCCIN44  POWER  = PVCCIN_CPU1
  BN54  VCCIN45  POWER  = PVCCIN_CPU1
